(kicad_pcb
	(version 20260206)
	(generator "pcbnew")
	(generator_version "10.0")
	(general
		(thickness 1.6)
		(legacy_teardrops no)
	)
	(paper "A4")
	(title_block
		(title "Bryce Canyon_R.DPB_16317-1_OCP.brd")
		(comment 1 "Bryce Canyon / footprints 1455-1461 of 2099")
	)
	(layers
		(0 "F.Cu" signal "TOP")
		(4 "In1.Cu" signal "L2GND")
		(6 "In2.Cu" signal "L3")
		(8 "In3.Cu" signal "L4VCC")
		(10 "In4.Cu" signal "L5VCC")
		(12 "In5.Cu" signal "L6")
		(14 "In6.Cu" signal "L7GND")
		(2 "B.Cu" signal "BOTTOM")
		(9 "F.Adhes" user "F.Adhesive")
		(11 "B.Adhes" user "B.Adhesive")
		(13 "F.Paste" user "Package Geometry/Pastemask Top")
		(15 "B.Paste" user "Package Geometry/Pastemask Bottom")
		(5 "F.SilkS" user "Ref Des/Silkscreen Top")
		(7 "B.SilkS" user "Ref Des/Silkscreen Bottom")
		(1 "F.Mask" user "Board Geometry/Soldermask Top")
		(3 "B.Mask" user "Board Geometry/Soldermask Bottom")
		(17 "Dwgs.User" user "User.Drawings")
		(19 "Cmts.User" user "User.Comments")
		(21 "Eco1.User" user "User.Eco1")
		(23 "Eco2.User" user "User.Eco2")
		(25 "Edge.Cuts" user "Board Geometry/Outline")
		(27 "Margin" user)
		(31 "F.CrtYd" user "Package Geometry/Place Bound Top")
		(29 "B.CrtYd" user "Package Geometry/Place Bound Bottom")
		(35 "F.Fab" user "Ref Des/Assembly Top")
		(33 "B.Fab" user "Ref Des/Assembly Bottom")
	)
	(footprint ""
		(layer "F.Cu")
		(at 474.6752 -6.8072 180)
		(property "Reference" "D35"
			(at 0 0 180)
			(layer "F.SilkS")
			(hide yes)
			(effects
				(font
					(size 1.27 1.27)
				)
			)
		)
		(property "Value" "RB551V30-GP"
			(at 0 -6.7818 180)
			(unlocked yes)
			(layer "F.Fab")
			(hide yes)
			(effects
				(font
					(size 1.016 1.016)
					(thickness 0.1524)
				)
			)
		)
		(property "Device Type" "SOD323AKH38"
			(at 0 -8.6868 180)
			(unlocked yes)
			(layer "F.Fab")
			(hide yes)
			(effects
				(font
					(size 1.016 1.016)
					(thickness 0.1524)
				)
			)
		)
		(duplicate_pad_numbers_are_jumpers no)
		(fp_line
			(start 0.889 2.159)
			(end -0.889 2.159)
			(stroke
				(width 0.1524)
				(type default)
			)
			(layer "F.SilkS")
		)
		(fp_line
			(start 0.889 -1.9304)
			(end 0.889 2.159)
			(stroke
				(width 0.1524)
				(type default)
			)
			(layer "F.SilkS")
		)
		(fp_line
			(start 0.762 2.0574)
			(end -0.762 2.0574)
			(stroke
				(width 0.508)
				(type default)
			)
			(layer "F.SilkS")
		)
		(fp_line
			(start -0.889 2.159)
			(end -0.889 -1.9304)
			(stroke
				(width 0.1524)
				(type default)
			)
			(layer "F.SilkS")
		)
		(fp_line
			(start -0.889 -1.9304)
			(end 0.889 -1.9304)
			(stroke
				(width 0.1524)
				(type default)
			)
			(layer "F.SilkS")
		)
		(fp_rect
			(start -1.016 2.3114)
			(end 1.016 -2.0066)
			(stroke
				(width 0)
				(type default)
			)
			(fill no)
			(layer "F.CrtYd")
		)
		(fp_poly
			(pts
				(xy -1.016 -2.0066) (xy 1.016 -2.0066) (xy 1.016 2.3114) (xy -1.016 2.3114)
			)
			(stroke
				(width 0)
				(type default)
			)
			(fill no)
			(layer "F.Fab")
		)
		(pad "A" smd rect
			(at 0 -1.143 180)
			(size 0.5588 1.016)
			(layers "F.Cu" "F.Mask" "F.Paste")
			(net "SW_HDD_R35")
		)
		(pad "K" smd rect
			(at 0 1.143 180)
			(size 0.5588 1.016)
			(layers "F.Cu" "F.Mask" "F.Paste")
			(net "SW_HDD_N35")
		)
	)
	(footprint ""
		(layer "F.Cu")
		(at 392.938 -160.401 180)
		(property "Reference" "C296"
			(at 0 0 180)
			(layer "F.SilkS")
			(hide yes)
			(effects
				(font
					(size 1.27 1.27)
				)
			)
		)
		(property "Value" "SC1U25V3KX-GP"
			(at 0 -2.8194 180)
			(unlocked yes)
			(layer "F.Fab")
			(hide yes)
			(effects
				(font
					(size 1.016 1.016)
					(thickness 0.1524)
				)
			)
		)
		(property "Device Type" "C603H36"
			(at 0 -4.3434 180)
			(unlocked yes)
			(layer "F.Fab")
			(hide yes)
			(effects
				(font
					(size 1.016 1.016)
					(thickness 0.1524)
				)
			)
		)
		(duplicate_pad_numbers_are_jumpers no)
		(fp_line
			(start 0.508 0)
			(end -0.508 0)
			(stroke
				(width 0.2032)
				(type default)
			)
			(layer "F.SilkS")
		)
		(fp_rect
			(start -0.5842 1.3335)
			(end 0.5842 -1.3335)
			(stroke
				(width 0)
				(type default)
			)
			(fill no)
			(layer "F.CrtYd")
		)
		(fp_rect
			(start -0.5842 1.3335)
			(end 0.5842 -1.3335)
			(stroke
				(width 0)
				(type default)
			)
			(fill no)
			(layer "F.Fab")
		)
		(pad "1" smd custom
			(at 0 -0.762 180)
			(size 0.2159 0.2159)
			(layers "F.Cu" "F.Mask" "F.Paste")
			(net "P12V_HDD20")
			(options
				(clearance outline)
				(anchor circle)
			)
			(primitives
				(gr_poly
					(pts
						(arc
							(start -0.3302 -0.4318)
							(mid -0.402042 -0.402042)
							(end -0.4318 -0.3302)
						)
						(arc
							(start -0.4318 0.3302)
							(mid -0.402042 0.402042)
							(end -0.3302 0.4318)
						)
						(arc
							(start 0.3302 0.4318)
							(mid 0.402042 0.402042)
							(end 0.4318 0.3302)
						)
						(arc
							(start 0.4318 -0.3302)
							(mid 0.402042 -0.402042)
							(end 0.3302 -0.4318)
						)
					)
					(width 0)
					(fill yes)
				)
			)
		)
		(pad "2" smd custom
			(at 0 0.762 180)
			(size 0.2159 0.2159)
			(layers "F.Cu" "F.Mask" "F.Paste")
			(net "GND")
			(options
				(clearance outline)
				(anchor circle)
			)
			(primitives
				(gr_poly
					(pts
						(arc
							(start -0.3302 -0.4318)
							(mid -0.402042 -0.402042)
							(end -0.4318 -0.3302)
						)
						(arc
							(start -0.4318 0.3302)
							(mid -0.402042 0.402042)
							(end -0.3302 0.4318)
						)
						(arc
							(start 0.3302 0.4318)
							(mid 0.402042 0.402042)
							(end 0.4318 0.3302)
						)
						(arc
							(start 0.4318 -0.3302)
							(mid 0.402042 -0.402042)
							(end 0.3302 -0.4318)
						)
					)
					(width 0)
					(fill yes)
				)
			)
		)
	)
	(footprint ""
		(layer "F.Cu")
		(at 146.304 -146.939 -90)
		(property "Reference" "C239"
			(at 0 0 270)
			(layer "F.SilkS")
			(hide yes)
			(effects
				(font
					(size 1.27 1.27)
				)
			)
		)
		(property "Value" "SC10U16V6KX-2GP"
			(at -0.0762 -5.1308 270)
			(unlocked yes)
			(layer "F.Fab")
			(hide yes)
			(effects
				(font
					(size 1.016 1.016)
					(thickness 0.1524)
				)
			)
		)
		(property "Device Type" "C1206H71"
			(at -0.127 -6.6548 270)
			(unlocked yes)
			(layer "F.Fab")
			(hide yes)
			(effects
				(font
					(size 1.016 1.016)
					(thickness 0.1524)
				)
			)
		)
		(duplicate_pad_numbers_are_jumpers no)
		(fp_line
			(start -1.016 2.2352)
			(end -1.016 0.8382)
			(stroke
				(width 0.1524)
				(type default)
			)
			(layer "F.SilkS")
		)
		(fp_line
			(start 1.016 2.2352)
			(end -1.016 2.2352)
			(stroke
				(width 0.1524)
				(type default)
			)
			(layer "F.SilkS")
		)
		(fp_line
			(start 1.016 0.8382)
			(end 1.016 2.2352)
			(stroke
				(width 0.1524)
				(type default)
			)
			(layer "F.SilkS")
		)
		(fp_line
			(start -1.016 -0.8382)
			(end -1.016 -2.2352)
			(stroke
				(width 0.1524)
				(type default)
			)
			(layer "F.SilkS")
		)
		(fp_line
			(start -1.016 -2.2352)
			(end 1.016 -2.2352)
			(stroke
				(width 0.1524)
				(type default)
			)
			(layer "F.SilkS")
		)
		(fp_line
			(start 1.016 -2.2352)
			(end 1.016 -0.8382)
			(stroke
				(width 0.1524)
				(type default)
			)
			(layer "F.SilkS")
		)
		(fp_rect
			(start -1.0922 2.3114)
			(end 1.0922 -2.3114)
			(stroke
				(width 0)
				(type default)
			)
			(fill no)
			(layer "F.CrtYd")
		)
		(fp_poly
			(pts
				(xy 1.0922 -2.3114) (xy 1.0922 2.3114) (xy -1.0922 2.3114) (xy -1.0922 -2.3114)
			)
			(stroke
				(width 0)
				(type default)
			)
			(fill no)
			(layer "F.Fab")
		)
		(pad "1" smd rect
			(at 0 -1.397 270)
			(size 1.651 1.27)
			(layers "F.Cu" "F.Mask" "F.Paste")
			(net "P5V_HDD16")
		)
		(pad "2" smd rect
			(at 0 1.397 270)
			(size 1.651 1.27)
			(layers "F.Cu" "F.Mask" "F.Paste")
			(net "GND")
		)
	)
	(footprint ""
		(layer "F.Cu")
		(at 444.159386 -121.312178 -90)
		(property "Reference" "R1155"
			(at 0 0 270)
			(layer "F.SilkS")
			(hide yes)
			(effects
				(font
					(size 1.27 1.27)
				)
			)
		)
		(property "Value" "0R2J-2-GP"
			(at 0.064008 -3.993896 270)
			(unlocked yes)
			(layer "F.Fab")
			(hide yes)
			(effects
				(font
					(size 1.016 1.016)
					(thickness 0.1524)
				)
			)
		)
		(property "Device Type" "R402H16"
			(at 0.064008 -5.517896 270)
			(unlocked yes)
			(layer "F.Fab")
			(hide yes)
			(effects
				(font
					(size 1.016 1.016)
					(thickness 0.1524)
				)
			)
		)
		(duplicate_pad_numbers_are_jumpers no)
		(fp_line
			(start -0.508 -0.9398)
			(end -0.508 0.9398)
			(stroke
				(width 0.1524)
				(type default)
			)
			(layer "F.SilkS")
		)
		(fp_line
			(start 0.508 -0.9398)
			(end -0.508 -0.9398)
			(stroke
				(width 0.1524)
				(type default)
			)
			(layer "F.SilkS")
		)
		(fp_rect
			(start -0.508 0.9398)
			(end 0.508 -0.9398)
			(stroke
				(width 0)
				(type default)
			)
			(fill no)
			(layer "F.CrtYd")
		)
		(fp_rect
			(start -0.508 0.9398)
			(end 0.508 -0.9398)
			(stroke
				(width 0)
				(type default)
			)
			(fill no)
			(layer "F.Fab")
		)
		(pad "1" smd custom
			(at 0 -0.4445 270)
			(size 0.1397 0.1397)
			(layers "F.Cu" "F.Mask" "F.Paste")
			(net "P12V_B_PGOOD")
			(options
				(clearance outline)
				(anchor circle)
			)
			(primitives
				(gr_poly
					(pts
						(arc
							(start -0.1778 -0.2794)
							(mid -0.249642 -0.249642)
							(end -0.2794 -0.1778)
						)
						(arc
							(start -0.2794 0.1778)
							(mid -0.249642 0.249642)
							(end -0.1778 0.2794)
						)
						(arc
							(start 0.1778 0.2794)
							(mid 0.249642 0.249642)
							(end 0.2794 0.1778)
						)
						(arc
							(start 0.2794 -0.1778)
							(mid 0.249642 -0.249642)
							(end 0.1778 -0.2794)
						)
					)
					(width 0)
					(fill yes)
				)
			)
		)
		(pad "2" smd custom
			(at 0 0.4445 270)
			(size 0.1397 0.1397)
			(layers "F.Cu" "F.Mask" "F.Paste")
			(net "P5V_B_4_EN_R")
			(options
				(clearance outline)
				(anchor circle)
			)
			(primitives
				(gr_poly
					(pts
						(arc
							(start -0.1778 -0.2794)
							(mid -0.249642 -0.249642)
							(end -0.2794 -0.1778)
						)
						(arc
							(start -0.2794 0.1778)
							(mid -0.249642 0.249642)
							(end -0.1778 0.2794)
						)
						(arc
							(start 0.1778 0.2794)
							(mid 0.249642 0.249642)
							(end 0.2794 0.1778)
						)
						(arc
							(start 0.2794 -0.1778)
							(mid 0.249642 -0.249642)
							(end 0.1778 -0.2794)
						)
					)
					(width 0)
					(fill yes)
				)
			)
		)
	)
	(footprint ""
		(layer "F.Cu")
		(at 263.1059 -380.216156 -90)
		(property "Reference" "R1069"
			(at 0 0 270)
			(layer "F.SilkS")
			(hide yes)
			(effects
				(font
					(size 1.27 1.27)
				)
			)
		)
		(property "Value" "1KR2J-1-GP"
			(at 0.064008 -3.993896 270)
			(unlocked yes)
			(layer "F.Fab")
			(hide yes)
			(effects
				(font
					(size 1.016 1.016)
					(thickness 0.1524)
				)
			)
		)
		(property "Device Type" "R402H16"
			(at 0.064008 -5.517896 270)
			(unlocked yes)
			(layer "F.Fab")
			(hide yes)
			(effects
				(font
					(size 1.016 1.016)
					(thickness 0.1524)
				)
			)
		)
		(duplicate_pad_numbers_are_jumpers no)
		(fp_line
			(start -0.508 -0.9398)
			(end -0.508 0.9398)
			(stroke
				(width 0.1524)
				(type default)
			)
			(layer "F.SilkS")
		)
		(fp_line
			(start 0.508 -0.9398)
			(end -0.508 -0.9398)
			(stroke
				(width 0.1524)
				(type default)
			)
			(layer "F.SilkS")
		)
		(fp_rect
			(start -0.508 0.9398)
			(end 0.508 -0.9398)
			(stroke
				(width 0)
				(type default)
			)
			(fill no)
			(layer "F.CrtYd")
		)
		(fp_rect
			(start -0.508 0.9398)
			(end 0.508 -0.9398)
			(stroke
				(width 0)
				(type default)
			)
			(fill no)
			(layer "F.Fab")
		)
		(pad "1" smd custom
			(at 0 -0.4445 270)
			(size 0.1397 0.1397)
			(layers "F.Cu" "F.Mask" "F.Paste")
			(net "DRAWER_OUT_NET")
			(options
				(clearance outline)
				(anchor circle)
			)
			(primitives
				(gr_poly
					(pts
						(arc
							(start -0.1778 -0.2794)
							(mid -0.249642 -0.249642)
							(end -0.2794 -0.1778)
						)
						(arc
							(start -0.2794 0.1778)
							(mid -0.249642 0.249642)
							(end -0.1778 0.2794)
						)
						(arc
							(start 0.1778 0.2794)
							(mid 0.249642 0.249642)
							(end 0.2794 0.1778)
						)
						(arc
							(start 0.2794 -0.1778)
							(mid 0.249642 -0.249642)
							(end 0.1778 -0.2794)
						)
					)
					(width 0)
					(fill yes)
				)
			)
		)
		(pad "2" smd custom
			(at 0 0.4445 270)
			(size 0.1397 0.1397)
			(layers "F.Cu" "F.Mask" "F.Paste")
			(net "GND")
			(options
				(clearance outline)
				(anchor circle)
			)
			(primitives
				(gr_poly
					(pts
						(arc
							(start -0.1778 -0.2794)
							(mid -0.249642 -0.249642)
							(end -0.2794 -0.1778)
						)
						(arc
							(start -0.2794 0.1778)
							(mid -0.249642 0.249642)
							(end -0.1778 0.2794)
						)
						(arc
							(start 0.1778 0.2794)
							(mid 0.249642 0.249642)
							(end 0.2794 0.1778)
						)
						(arc
							(start 0.2794 -0.1778)
							(mid 0.249642 -0.249642)
							(end 0.1778 -0.2794)
						)
					)
					(width 0)
					(fill yes)
				)
			)
		)
	)
	(footprint ""
		(layer "F.Cu")
		(at 395.224 -246.253 -90)
		(property "Reference" "Q31"
			(at 0 0 270)
			(layer "F.SilkS")
			(hide yes)
			(effects
				(font
					(size 1.27 1.27)
				)
			)
		)
		(property "Value" "2N7002KDW-GP"
			(at -2.3622 -8.2042 270)
			(unlocked yes)
			(layer "F.Fab")
			(hide yes)
			(effects
				(font
					(size 1.016 1.016)
					(thickness 0.1524)
				)
			)
		)
		(property "Device Type" "SOT-363H44"
			(at -2.3622 -10.1092 270)
			(unlocked yes)
			(layer "F.Fab")
			(hide yes)
			(effects
				(font
					(size 1.016 1.016)
					(thickness 0.1524)
				)
			)
		)
		(duplicate_pad_numbers_are_jumpers no)
		(fp_line
			(start -1.4478 1.7018)
			(end 1.4478 1.7018)
			(stroke
				(width 0.1524)
				(type default)
			)
			(layer "F.SilkS")
		)
		(fp_line
			(start 1.4478 1.7018)
			(end 1.4478 -1.7018)
			(stroke
				(width 0.1524)
				(type default)
			)
			(layer "F.SilkS")
		)
		(fp_line
			(start -1.27 1.524)
			(end -1.27 0.6604)
			(stroke
				(width 0.4826)
				(type default)
			)
			(layer "F.SilkS")
		)
		(fp_line
			(start -1.4478 -1.7018)
			(end -1.4478 1.7018)
			(stroke
				(width 0.1524)
				(type default)
			)
			(layer "F.SilkS")
		)
		(fp_line
			(start 1.4478 -1.7018)
			(end -1.4478 -1.7018)
			(stroke
				(width 0.1524)
				(type default)
			)
			(layer "F.SilkS")
		)
		(fp_poly
			(pts
				(xy -1.524 -1.778) (xy 1.524 -1.778) (xy 1.524 1.778) (xy -1.524 1.778)
			)
			(stroke
				(width 0)
				(type default)
			)
			(fill no)
			(layer "F.CrtYd")
		)
		(fp_poly
			(pts
				(xy -1.524 -1.778) (xy 1.524 -1.778) (xy 1.524 1.778) (xy -1.524 1.778)
			)
			(stroke
				(width 0)
				(type default)
			)
			(fill no)
			(layer "F.Fab")
		)
		(pad "1" smd rect
			(at -0.65024 0.9398 270)
			(size 0.4064 1.016)
			(layers "F.Cu" "F.Mask" "F.Paste")
			(net "GND")
		)
		(pad "2" smd rect
			(at 0 0.9398 270)
			(size 0.4064 1.016)
			(layers "F.Cu" "F.Mask" "F.Paste")
			(net "SW_PWR_R_HDD8")
		)
		(pad "3" smd rect
			(at 0.65024 0.9398 270)
			(size 0.4064 1.016)
			(layers "F.Cu" "F.Mask" "F.Paste")
			(net "SW_HDD_P8")
		)
		(pad "4" smd rect
			(at 0.65024 -0.9398 270)
			(size 0.4064 1.016)
			(layers "F.Cu" "F.Mask" "F.Paste")
			(net "GND")
		)
		(pad "5" smd rect
			(at 0 -0.9398 270)
			(size 0.4064 1.016)
			(layers "F.Cu" "F.Mask" "F.Paste")
			(net "SW_HDD_G8")
		)
		(pad "6" smd rect
			(at -0.65024 -0.9398 270)
			(size 0.4064 1.016)
			(layers "F.Cu" "F.Mask" "F.Paste")
			(net "SW_HDD_R8")
		)
	)
	(footprint ""
		(layer "F.Cu")
		(at 79.883 -24.13 -90)
		(property "Reference" "C376"
			(at 0 0 270)
			(layer "F.SilkS")
			(hide yes)
			(effects
				(font
					(size 1.27 1.27)
				)
			)
		)
		(property "Value" "SCD033U25V2KX-GP"
			(at 1.1811 -2.7051 270)
			(unlocked yes)
			(layer "F.Fab")
			(hide yes)
			(effects
				(font
					(size 1.016 1.016)
					(thickness 0.1524)
				)
			)
		)
		(property "Device Type" "C402H22"
			(at 1.1811 -4.2291 270)
			(unlocked yes)
			(layer "F.Fab")
			(hide yes)
			(effects
				(font
					(size 1.016 1.016)
					(thickness 0.1524)
				)
			)
		)
		(duplicate_pad_numbers_are_jumpers no)
		(fp_rect
			(start -0.4318 0.9525)
			(end 0.4318 -0.9525)
			(stroke
				(width 0)
				(type default)
			)
			(fill no)
			(layer "F.CrtYd")
		)
		(fp_rect
			(start -0.4318 0.9525)
			(end 0.4318 -0.9525)
			(stroke
				(width 0)
				(type default)
			)
			(fill no)
			(layer "F.Fab")
		)
		(pad "1" smd custom
			(at 0 -0.4445 270)
			(size 0.1524 0.1524)
			(layers "F.Cu" "F.Mask" "F.Paste")
			(net "SW_HDD_P26")
			(options
				(clearance outline)
				(anchor circle)
			)
			(primitives
				(gr_poly
					(pts
						(arc
							(start 0.3048 -0.2032)
							(mid 0.275042 -0.275042)
							(end 0.2032 -0.3048)
						)
						(arc
							(start -0.2032 -0.3048)
							(mid -0.275042 -0.275042)
							(end -0.3048 -0.2032)
						)
						(arc
							(start -0.3048 0.2032)
							(mid -0.275042 0.275042)
							(end -0.2032 0.3048)
						)
						(arc
							(start 0.2032 0.3048)
							(mid 0.275042 0.275042)
							(end 0.3048 0.2032)
						)
					)
					(width 0)
					(fill yes)
				)
			)
		)
		(pad "2" smd custom
			(at 0 0.4445 270)
			(size 0.1524 0.1524)
			(layers "F.Cu" "F.Mask" "F.Paste")
			(net "GND")
			(options
				(clearance outline)
				(anchor circle)
			)
			(primitives
				(gr_poly
					(pts
						(arc
							(start 0.3048 -0.2032)
							(mid 0.275042 -0.275042)
							(end 0.2032 -0.3048)
						)
						(arc
							(start -0.2032 -0.3048)
							(mid -0.275042 -0.275042)
							(end -0.3048 -0.2032)
						)
						(arc
							(start -0.3048 0.2032)
							(mid -0.275042 0.275042)
							(end -0.2032 0.3048)
						)
						(arc
							(start 0.2032 0.3048)
							(mid 0.275042 0.275042)
							(end 0.3048 0.2032)
						)
					)
					(width 0)
					(fill yes)
				)
			)
		)
	)
)
